# T6G (Grand Teton) — schematic netlist excerpt (pin names and nets, part order shuffled) for the footprints in the layout excerpt that follows; sources: Cadence DE-HDL packaged netlist, KiCad conversion of 04192023_DAF0TMB3IC0_F0TG_MB_C_brd_V02_OCP.brd

C1522  Q_CAP  0.1UF 16V 10% X7R  pkg C0402  page 174 : A = PVDD18_S5_P0 ; B = GND
PR62  Q_RES  0 5% CHIP  pkg 0402LF  page 200 : A = SVID_PVDDCR_CPU1_P0_SVTI ; B = SVID_PVDDCR_CPU1_P0_SVTI_R

(kicad_pcb
	(version 20260206)
	(generator "pcbnew")
	(generator_version "10.0")
	(general
		(thickness 1.6)
		(legacy_teardrops no)
	)
	(paper "A4")
	(title_block
		(title "04192023_DAF0TMB3IC0_F0TG_MB_C_brd_V02_OCP.brd")
		(comment 1 "Grand Teton / footprints 628-629 of 8354")
	)
	(layers
		(0 "F.Cu" signal "TOP")
		(4 "In1.Cu" signal "GND")
		(6 "In2.Cu" signal "IN1")
		(8 "In3.Cu" signal "GND1")
		(10 "In4.Cu" signal "IN2")
		(12 "In5.Cu" signal "GND2")
		(14 "In6.Cu" signal "IN3")
		(16 "In7.Cu" signal "GND3")
		(18 "In8.Cu" signal "VCC")
		(20 "In9.Cu" signal "VCC1")
		(22 "In10.Cu" signal "GND4")
		(24 "In11.Cu" signal "IN4")
		(26 "In12.Cu" signal "GND5")
		(28 "In13.Cu" signal "IN5")
		(30 "In14.Cu" signal "GND6")
		(32 "In15.Cu" signal "IN6")
		(34 "In16.Cu" signal "GND7")
		(2 "B.Cu" signal "BOTTOM")
		(9 "F.Adhes" user "F.Adhesive")
		(11 "B.Adhes" user "B.Adhesive")
		(13 "F.Paste" user "Package Geometry/Pastemask Top")
		(15 "B.Paste" user "Package Geometry/Pastemask Bottom")
		(5 "F.SilkS" user "Ref Des/Silkscreen Top")
		(7 "B.SilkS" user "Ref Des/Silkscreen Bottom")
		(1 "F.Mask" user "Board Geometry/Soldermask Top")
		(3 "B.Mask" user "Board Geometry/Soldermask Bottom")
		(17 "Dwgs.User" user "User.Drawings")
		(19 "Cmts.User" user "User.Comments")
		(21 "Eco1.User" user "User.Eco1")
		(23 "Eco2.User" user "User.Eco2")
		(25 "Edge.Cuts" user "Board Geometry/Outline")
		(27 "Margin" user)
		(31 "F.CrtYd" user "Package Geometry/Place Bound Top")
		(29 "B.CrtYd" user "Package Geometry/Place Bound Bottom")
		(35 "F.Fab" user "Ref Des/Assembly Top")
		(33 "B.Fab" user "Ref Des/Assembly Bottom")
	)
	(footprint ""
		(layer "F.Cu")
		(at 229.903274 -155.284932 180)
		(property "Reference" "C1522"
			(at 0 0 180)
			(layer "F.SilkS")
			(hide yes)
			(effects
				(font
					(size 1.27 1.27)
				)
			)
		)
		(property "Value" ""
			(at 0 0 180)
			(layer "F.Fab")
			(effects
				(font
					(size 1.27 1.27)
				)
			)
		)
		(duplicate_pad_numbers_are_jumpers no)
		(fp_line
			(start 0.7874 0.4064)
			(end -0.7874 0.4064)
			(stroke
				(width 0.1524)
				(type default)
			)
			(layer "F.SilkS")
		)
		(fp_line
			(start 0.7874 -0.4064)
			(end 0.7874 0.4064)
			(stroke
				(width 0.1524)
				(type default)
			)
			(layer "F.SilkS")
		)
		(fp_line
			(start -0.7874 0.4064)
			(end -0.7874 -0.4064)
			(stroke
				(width 0.1524)
				(type default)
			)
			(layer "F.SilkS")
		)
		(fp_line
			(start -0.7874 -0.4064)
			(end 0.7874 -0.4064)
			(stroke
				(width 0.1524)
				(type default)
			)
			(layer "F.SilkS")
		)
		(fp_line
			(start 0.67945 0.3048)
			(end 0.120396 0.3048)
			(stroke
				(width 0.1)
				(type default)
			)
			(layer "F.Fab")
		)
		(fp_line
			(start 0.67945 -0.3048)
			(end 0.67945 0.3048)
			(stroke
				(width 0.1)
				(type default)
			)
			(layer "F.Fab")
		)
		(fp_line
			(start 0.12065 -0.2794)
			(end 0.12065 -0.3048)
			(stroke
				(width 0.1)
				(type default)
			)
			(layer "F.Fab")
		)
		(fp_line
			(start 0.12065 -0.3048)
			(end 0.67945 -0.3048)
			(stroke
				(width 0.1)
				(type default)
			)
			(layer "F.Fab")
		)
		(fp_line
			(start 0.120396 0.3048)
			(end 0.120396 0.2794)
			(stroke
				(width 0.1)
				(type default)
			)
			(layer "F.Fab")
		)
		(fp_line
			(start 0.120396 0.2794)
			(end -0.12065 0.2794)
			(stroke
				(width 0.1)
				(type default)
			)
			(layer "F.Fab")
		)
		(fp_line
			(start -0.12065 0.3048)
			(end -0.67945 0.3048)
			(stroke
				(width 0.1)
				(type default)
			)
			(layer "F.Fab")
		)
		(fp_line
			(start -0.12065 0.2794)
			(end -0.12065 0.3048)
			(stroke
				(width 0.1)
				(type default)
			)
			(layer "F.Fab")
		)
		(fp_line
			(start -0.12065 -0.2794)
			(end 0.12065 -0.2794)
			(stroke
				(width 0.1)
				(type default)
			)
			(layer "F.Fab")
		)
		(fp_line
			(start -0.12065 -0.305054)
			(end -0.12065 -0.2794)
			(stroke
				(width 0.1)
				(type default)
			)
			(layer "F.Fab")
		)
		(fp_line
			(start -0.67945 0.3048)
			(end -0.67945 -0.305054)
			(stroke
				(width 0.1)
				(type default)
			)
			(layer "F.Fab")
		)
		(fp_line
			(start -0.67945 -0.305054)
			(end -0.12065 -0.305054)
			(stroke
				(width 0.1)
				(type default)
			)
			(layer "F.Fab")
		)
		(pad "1" smd circle
			(at -0.40005 0 180)
			(size 0 0)
			(layers "F.Cu" "F.Mask" "F.Paste")
			(net "PVDD18_S5_P0")
		)
		(pad "2" smd circle
			(at 0.40005 0 180)
			(size 0 0)
			(layers "F.Cu" "F.Mask" "F.Paste")
			(net "GND")
		)
	)
	(footprint ""
		(layer "F.Cu")
		(at 304.419 -354.711)
		(property "Reference" "PR62"
			(at 0 0 0)
			(layer "F.SilkS")
			(hide yes)
			(effects
				(font
					(size 1.27 1.27)
				)
			)
		)
		(property "Value" ""
			(at 0 0 0)
			(layer "F.Fab")
			(effects
				(font
					(size 1.27 1.27)
				)
			)
		)
		(duplicate_pad_numbers_are_jumpers no)
		(fp_line
			(start -0.7874 -0.4064)
			(end 0.7874 -0.4064)
			(stroke
				(width 0.1524)
				(type default)
			)
			(layer "F.SilkS")
		)
		(fp_line
			(start -0.7874 0.4064)
			(end -0.7874 -0.4064)
			(stroke
				(width 0.1524)
				(type default)
			)
			(layer "F.SilkS")
		)
		(fp_line
			(start 0.7874 -0.4064)
			(end 0.7874 0.4064)
			(stroke
				(width 0.1524)
				(type default)
			)
			(layer "F.SilkS")
		)
		(fp_line
			(start 0.7874 0.4064)
			(end -0.7874 0.4064)
			(stroke
				(width 0.1524)
				(type default)
			)
			(layer "F.SilkS")
		)
		(fp_line
			(start -0.67945 -0.305054)
			(end -0.12065 -0.305054)
			(stroke
				(width 0.1)
				(type default)
			)
			(layer "F.Fab")
		)
		(fp_line
			(start -0.67945 0.3048)
			(end -0.67945 -0.305054)
			(stroke
				(width 0.1)
				(type default)
			)
			(layer "F.Fab")
		)
		(fp_line
			(start -0.12065 -0.305054)
			(end -0.12065 -0.2794)
			(stroke
				(width 0.1)
				(type default)
			)
			(layer "F.Fab")
		)
		(fp_line
			(start -0.12065 -0.2794)
			(end 0.12065 -0.2794)
			(stroke
				(width 0.1)
				(type default)
			)
			(layer "F.Fab")
		)
		(fp_line
			(start -0.12065 0.2794)
			(end -0.12065 0.3048)
			(stroke
				(width 0.1)
				(type default)
			)
			(layer "F.Fab")
		)
		(fp_line
			(start -0.12065 0.3048)
			(end -0.67945 0.3048)
			(stroke
				(width 0.1)
				(type default)
			)
			(layer "F.Fab")
		)
		(fp_line
			(start 0.120396 0.2794)
			(end -0.12065 0.2794)
			(stroke
				(width 0.1)
				(type default)
			)
			(layer "F.Fab")
		)
		(fp_line
			(start 0.120396 0.3048)
			(end 0.120396 0.2794)
			(stroke
				(width 0.1)
				(type default)
			)
			(layer "F.Fab")
		)
		(fp_line
			(start 0.12065 -0.3048)
			(end 0.67945 -0.3048)
			(stroke
				(width 0.1)
				(type default)
			)
			(layer "F.Fab")
		)
		(fp_line
			(start 0.12065 -0.2794)
			(end 0.12065 -0.3048)
			(stroke
				(width 0.1)
				(type default)
			)
			(layer "F.Fab")
		)
		(fp_line
			(start 0.67945 -0.3048)
			(end 0.67945 0.3048)
			(stroke
				(width 0.1)
				(type default)
			)
			(layer "F.Fab")
		)
		(fp_line
			(start 0.67945 0.3048)
			(end 0.120396 0.3048)
			(stroke
				(width 0.1)
				(type default)
			)
			(layer "F.Fab")
		)
		(pad "1" smd circle
			(at -0.40005 0)
			(size 0 0)
			(layers "F.Cu" "F.Mask" "F.Paste")
			(net "SVID_PVDDCR_CPU1_P0_SVTI")
		)
		(pad "2" smd circle
			(at 0.40005 0)
			(size 0 0)
			(layers "F.Cu" "F.Mask" "F.Paste")
			(net "SVID_PVDDCR_CPU1_P0_SVTI_R")
		)
	)
)
